# SCM (Grand Teton) — schematic netlist excerpt (pin names and nets, part order shuffled) for the footprints in the layout excerpt that follows; sources: Cadence DE-HDL packaged netlist, KiCad conversion of 12092022_DA0F0TMDCD0_F0T_Management_Board_D_brd_V3_OCP.brd

R293  Q_RES  0 5% CHIP  pkg 0402LF  page 52 : A = PWRGD_P3V3_AUX_R ; B = PWRGD_P3V3_AUX
C151  Q_CAP  0.001UF 50V 10% EMPTY  pkg C0402  page 52 : A = PWRGD_P3V3_AUX_R ; B = GND

(kicad_pcb
	(version 20260206)
	(generator "pcbnew")
	(generator_version "10.0")
	(general
		(thickness 1.6)
		(legacy_teardrops no)
	)
	(paper "A4")
	(title_block
		(title "12092022_DA0F0TMDCD0_F0T_Management_Board_D_brd_V3_OCP.brd")
		(comment 1 "Grand Teton / footprints 244-245 of 1440")
	)
	(layers
		(0 "F.Cu" signal "TOP")
		(4 "In1.Cu" signal "GND")
		(6 "In2.Cu" signal "IN1")
		(8 "In3.Cu" signal "GND1")
		(10 "In4.Cu" signal "IN2")
		(12 "In5.Cu" signal "VCC")
		(14 "In6.Cu" signal "VCC1")
		(16 "In7.Cu" signal "IN3")
		(18 "In8.Cu" signal "GND2")
		(20 "In9.Cu" signal "IN4")
		(22 "In10.Cu" signal "GND3")
		(2 "B.Cu" signal "BOTTOM")
		(9 "F.Adhes" user "F.Adhesive")
		(11 "B.Adhes" user "B.Adhesive")
		(13 "F.Paste" user "Package Geometry/Pastemask Top")
		(15 "B.Paste" user "Package Geometry/Pastemask Bottom")
		(5 "F.SilkS" user "Ref Des/Silkscreen Top")
		(7 "B.SilkS" user "Ref Des/Silkscreen Bottom")
		(1 "F.Mask" user "Board Geometry/Soldermask Top")
		(3 "B.Mask" user "Board Geometry/Soldermask Bottom")
		(17 "Dwgs.User" user "User.Drawings")
		(19 "Cmts.User" user "User.Comments")
		(21 "Eco1.User" user "User.Eco1")
		(23 "Eco2.User" user "User.Eco2")
		(25 "Edge.Cuts" user "Board Geometry/Outline")
		(27 "Margin" user)
		(31 "F.CrtYd" user "Package Geometry/Place Bound Top")
		(29 "B.CrtYd" user "Package Geometry/Place Bound Bottom")
		(35 "F.Fab" user "Ref Des/Assembly Top")
		(33 "B.Fab" user "Ref Des/Assembly Bottom")
	)
	(footprint ""
		(layer "F.Cu")
		(at 11.29538 -67.4116 -90)
		(property "Reference" "C151"
			(at 0 0 270)
			(layer "F.SilkS")
			(hide yes)
			(effects
				(font
					(size 1.27 1.27)
				)
			)
		)
		(property "Value" ""
			(at 0 0 270)
			(layer "F.Fab")
			(effects
				(font
					(size 1.27 1.27)
				)
			)
		)
		(duplicate_pad_numbers_are_jumpers no)
		(fp_line
			(start -0.7874 0.4064)
			(end -0.7874 -0.4064)
			(stroke
				(width 0.1524)
				(type default)
			)
			(layer "F.SilkS")
		)
		(fp_line
			(start 0.7874 0.4064)
			(end -0.7874 0.4064)
			(stroke
				(width 0.1524)
				(type default)
			)
			(layer "F.SilkS")
		)
		(fp_line
			(start -0.7874 -0.4064)
			(end 0.7874 -0.4064)
			(stroke
				(width 0.1524)
				(type default)
			)
			(layer "F.SilkS")
		)
		(fp_line
			(start 0.7874 -0.4064)
			(end 0.7874 0.4064)
			(stroke
				(width 0.1524)
				(type default)
			)
			(layer "F.SilkS")
		)
		(fp_line
			(start -0.67945 0.3048)
			(end -0.67945 -0.305054)
			(stroke
				(width 0.1)
				(type default)
			)
			(layer "F.Fab")
		)
		(fp_line
			(start -0.12065 0.3048)
			(end -0.67945 0.3048)
			(stroke
				(width 0.1)
				(type default)
			)
			(layer "F.Fab")
		)
		(fp_line
			(start 0.120396 0.3048)
			(end 0.120396 0.2794)
			(stroke
				(width 0.1)
				(type default)
			)
			(layer "F.Fab")
		)
		(fp_line
			(start 0.67945 0.3048)
			(end 0.120396 0.3048)
			(stroke
				(width 0.1)
				(type default)
			)
			(layer "F.Fab")
		)
		(fp_line
			(start -0.12065 0.2794)
			(end -0.12065 0.3048)
			(stroke
				(width 0.1)
				(type default)
			)
			(layer "F.Fab")
		)
		(fp_line
			(start 0.120396 0.2794)
			(end -0.12065 0.2794)
			(stroke
				(width 0.1)
				(type default)
			)
			(layer "F.Fab")
		)
		(fp_line
			(start -0.12065 -0.2794)
			(end 0.12065 -0.2794)
			(stroke
				(width 0.1)
				(type default)
			)
			(layer "F.Fab")
		)
		(fp_line
			(start 0.12065 -0.2794)
			(end 0.12065 -0.3048)
			(stroke
				(width 0.1)
				(type default)
			)
			(layer "F.Fab")
		)
		(fp_line
			(start 0.12065 -0.3048)
			(end 0.67945 -0.3048)
			(stroke
				(width 0.1)
				(type default)
			)
			(layer "F.Fab")
		)
		(fp_line
			(start 0.67945 -0.3048)
			(end 0.67945 0.3048)
			(stroke
				(width 0.1)
				(type default)
			)
			(layer "F.Fab")
		)
		(fp_line
			(start -0.67945 -0.305054)
			(end -0.12065 -0.305054)
			(stroke
				(width 0.1)
				(type default)
			)
			(layer "F.Fab")
		)
		(fp_line
			(start -0.12065 -0.305054)
			(end -0.12065 -0.2794)
			(stroke
				(width 0.1)
				(type default)
			)
			(layer "F.Fab")
		)
		(pad "1" smd circle
			(at -0.40005 0 270)
			(size 0 0)
			(layers "F.Cu" "F.Mask" "F.Paste")
			(net "PWRGD_P3V3_AUX_R")
		)
		(pad "2" smd circle
			(at 0.40005 0 270)
			(size 0 0)
			(layers "F.Cu" "F.Mask" "F.Paste")
			(net "GND")
		)
	)
	(footprint ""
		(layer "F.Cu")
		(at 12.7762 -67.2084)
		(property "Reference" "R293"
			(at 0 0 0)
			(layer "F.SilkS")
			(hide yes)
			(effects
				(font
					(size 1.27 1.27)
				)
			)
		)
		(property "Value" ""
			(at 0 0 0)
			(layer "F.Fab")
			(effects
				(font
					(size 1.27 1.27)
				)
			)
		)
		(duplicate_pad_numbers_are_jumpers no)
		(fp_line
			(start -0.7874 -0.4064)
			(end 0.7874 -0.4064)
			(stroke
				(width 0.1524)
				(type default)
			)
			(layer "F.SilkS")
		)
		(fp_line
			(start -0.7874 0.4064)
			(end -0.7874 -0.4064)
			(stroke
				(width 0.1524)
				(type default)
			)
			(layer "F.SilkS")
		)
		(fp_line
			(start 0.7874 -0.4064)
			(end 0.7874 0.4064)
			(stroke
				(width 0.1524)
				(type default)
			)
			(layer "F.SilkS")
		)
		(fp_line
			(start 0.7874 0.4064)
			(end -0.7874 0.4064)
			(stroke
				(width 0.1524)
				(type default)
			)
			(layer "F.SilkS")
		)
		(fp_line
			(start -0.67945 -0.305054)
			(end -0.12065 -0.305054)
			(stroke
				(width 0.1)
				(type default)
			)
			(layer "F.Fab")
		)
		(fp_line
			(start -0.67945 0.3048)
			(end -0.67945 -0.305054)
			(stroke
				(width 0.1)
				(type default)
			)
			(layer "F.Fab")
		)
		(fp_line
			(start -0.12065 -0.305054)
			(end -0.12065 -0.2794)
			(stroke
				(width 0.1)
				(type default)
			)
			(layer "F.Fab")
		)
		(fp_line
			(start -0.12065 -0.2794)
			(end 0.12065 -0.2794)
			(stroke
				(width 0.1)
				(type default)
			)
			(layer "F.Fab")
		)
		(fp_line
			(start -0.12065 0.2794)
			(end -0.12065 0.3048)
			(stroke
				(width 0.1)
				(type default)
			)
			(layer "F.Fab")
		)
		(fp_line
			(start -0.12065 0.3048)
			(end -0.67945 0.3048)
			(stroke
				(width 0.1)
				(type default)
			)
			(layer "F.Fab")
		)
		(fp_line
			(start 0.120396 0.2794)
			(end -0.12065 0.2794)
			(stroke
				(width 0.1)
				(type default)
			)
			(layer "F.Fab")
		)
		(fp_line
			(start 0.120396 0.3048)
			(end 0.120396 0.2794)
			(stroke
				(width 0.1)
				(type default)
			)
			(layer "F.Fab")
		)
		(fp_line
			(start 0.12065 -0.3048)
			(end 0.67945 -0.3048)
			(stroke
				(width 0.1)
				(type default)
			)
			(layer "F.Fab")
		)
		(fp_line
			(start 0.12065 -0.2794)
			(end 0.12065 -0.3048)
			(stroke
				(width 0.1)
				(type default)
			)
			(layer "F.Fab")
		)
		(fp_line
			(start 0.67945 -0.3048)
			(end 0.67945 0.3048)
			(stroke
				(width 0.1)
				(type default)
			)
			(layer "F.Fab")
		)
		(fp_line
			(start 0.67945 0.3048)
			(end 0.120396 0.3048)
			(stroke
				(width 0.1)
				(type default)
			)
			(layer "F.Fab")
		)
		(pad "1" smd circle
			(at -0.40005 0)
			(size 0 0)
			(layers "F.Cu" "F.Mask" "F.Paste")
			(net "PWRGD_P3V3_AUX_R")
		)
		(pad "2" smd circle
			(at 0.40005 0)
			(size 0 0)
			(layers "F.Cu" "F.Mask" "F.Paste")
			(net "PWRGD_P3V3_AUX")
		)
	)
)
